(kicad_pcb
	(version 20260206)
	(generator "pcbnew")
	(generator_version "10.0")
	(general
		(thickness 1.6)
		(legacy_teardrops no)
	)
	(paper "A4")
	(title_block
		(title "Wiwynn_Tioga_Pass_MB.brd")
		(comment 1 "Tioga Pass / footprints 1935-1941 of 4770")
	)
	(layers
		(0 "F.Cu" signal "TOP")
		(4 "In1.Cu" signal "L2GND")
		(6 "In2.Cu" signal "L3")
		(8 "In3.Cu" signal "L4GND")
		(10 "In4.Cu" signal "L5")
		(12 "In5.Cu" signal "L6GND")
		(14 "In6.Cu" signal "L7VCC")
		(16 "In7.Cu" signal "L8VCC")
		(18 "In8.Cu" signal "L9GND")
		(20 "In9.Cu" signal "L10")
		(22 "In10.Cu" signal "L11GND")
		(24 "In11.Cu" signal "L12")
		(26 "In12.Cu" signal "L13GND")
		(2 "B.Cu" signal "BOTTOM")
		(9 "F.Adhes" user "F.Adhesive")
		(11 "B.Adhes" user "B.Adhesive")
		(13 "F.Paste" user "Package Geometry/Pastemask Top")
		(15 "B.Paste" user "Package Geometry/Pastemask Bottom")
		(5 "F.SilkS" user "Ref Des/Silkscreen Top")
		(7 "B.SilkS" user "Ref Des/Silkscreen Bottom")
		(1 "F.Mask" user "Board Geometry/Soldermask Top")
		(3 "B.Mask" user "Board Geometry/Soldermask Bottom")
		(17 "Dwgs.User" user "User.Drawings")
		(19 "Cmts.User" user "User.Comments")
		(21 "Eco1.User" user "User.Eco1")
		(23 "Eco2.User" user "User.Eco2")
		(25 "Edge.Cuts" user "Board Geometry/Outline")
		(27 "Margin" user)
		(31 "F.CrtYd" user "Package Geometry/Place Bound Top")
		(29 "B.CrtYd" user "Package Geometry/Place Bound Bottom")
		(35 "F.Fab" user "Ref Des/Assembly Top")
		(33 "B.Fab" user "Ref Des/Assembly Bottom")
	)
	(footprint ""
		(layer "F.Cu")
		(at 412.496 -18.415 90)
		(property "Reference" "C9G18"
			(at 0 0 90)
			(layer "F.SilkS")
			(hide yes)
			(effects
				(font
					(size 1.27 1.27)
				)
			)
		)
		(property "Value" ""
			(at 0 0 90)
			(layer "F.Fab")
			(effects
				(font
					(size 1.27 1.27)
				)
			)
		)
		(duplicate_pad_numbers_are_jumpers no)
		(fp_poly
			(pts
				(xy 0.3048 -0.1016) (xy 0.3048 0.9906) (xy -0.3048 0.9906) (xy -0.3048 -0.1016)
			)
			(stroke
				(width 0)
				(type default)
			)
			(fill no)
			(layer "F.CrtYd")
		)
		(fp_line
			(start 0.3048 -0.1016)
			(end -0.3048 -0.1016)
			(stroke
				(width 0.1)
				(type default)
			)
			(layer "F.Fab")
		)
		(fp_line
			(start -0.3048 -0.1016)
			(end -0.3048 0.9906)
			(stroke
				(width 0.1)
				(type default)
			)
			(layer "F.Fab")
		)
		(fp_line
			(start 0.3048 0.9906)
			(end 0.3048 -0.1016)
			(stroke
				(width 0.1)
				(type default)
			)
			(layer "F.Fab")
		)
		(fp_line
			(start -0.3048 0.9906)
			(end 0.3048 0.9906)
			(stroke
				(width 0.1)
				(type default)
			)
			(layer "F.Fab")
		)
		(pad "1" smd rect
			(at 0 0 90)
			(size 0.508 0.508)
			(layers "F.Cu" "F.Mask" "F.Paste")
			(net "A_PVNN_STBY_PCH_SENSOR")
		)
		(pad "2" smd rect
			(at 0 0.889 90)
			(size 0.508 0.508)
			(layers "F.Cu" "F.Mask" "F.Paste")
			(net "GND")
		)
		(zone
			(layer "F.Cu")
			(hatch none 0.5)
			(connect_pads
				(clearance 0)
			)
			(min_thickness 0.25)
			(keepout
				(tracks allowed)
				(vias not_allowed)
				(pads allowed)
				(copperpour not_allowed)
				(footprints allowed)
			)
			(placement
				(enabled no)
				(sheetname "")
			)
			(fill
				(thermal_gap 0.5)
				(thermal_bridge_width 0.5)
				(island_removal_mode 0)
			)
			(polygon
				(pts
					(xy 412.75 -18.161) (xy 412.75 -18.669) (xy 413.131 -18.669) (xy 413.131 -18.161)
				)
			)
		)
		(zone
			(layer "F.Cu")
			(hatch none 0.5)
			(connect_pads
				(clearance 0)
			)
			(min_thickness 0.25)
			(keepout
				(tracks not_allowed)
				(vias allowed)
				(pads allowed)
				(copperpour not_allowed)
				(footprints allowed)
			)
			(placement
				(enabled no)
				(sheetname "")
			)
			(fill
				(thermal_gap 0.5)
				(thermal_bridge_width 0.5)
				(island_removal_mode 0)
			)
			(polygon
				(pts
					(xy 413.131 -18.161) (xy 413.131 -18.669) (xy 412.75 -18.669) (xy 412.75 -18.161)
				)
			)
		)
	)
	(footprint ""
		(layer "F.Cu")
		(at 419.0492 -113.9952 180)
		(property "Reference" "R2M5"
			(at 0 0 180)
			(layer "F.SilkS")
			(hide yes)
			(effects
				(font
					(size 1.27 1.27)
				)
			)
		)
		(property "Value" ""
			(at 0 0 180)
			(layer "F.Fab")
			(effects
				(font
					(size 1.27 1.27)
				)
			)
		)
		(duplicate_pad_numbers_are_jumpers no)
		(fp_poly
			(pts
				(xy -0.2794 -0.1016) (xy 0.2794 -0.1016) (xy 0.2794 0.9906) (xy -0.2794 0.9906)
			)
			(stroke
				(width 0)
				(type default)
			)
			(fill no)
			(layer "F.CrtYd")
		)
		(fp_line
			(start 0.2794 0.9906)
			(end 0.2794 -0.1016)
			(stroke
				(width 0.1)
				(type default)
			)
			(layer "F.Fab")
		)
		(fp_line
			(start 0.2794 -0.1016)
			(end -0.2794 -0.1016)
			(stroke
				(width 0.1)
				(type default)
			)
			(layer "F.Fab")
		)
		(fp_line
			(start -0.2794 0.9906)
			(end 0.2794 0.9906)
			(stroke
				(width 0.1)
				(type default)
			)
			(layer "F.Fab")
		)
		(fp_line
			(start -0.2794 -0.1016)
			(end -0.2794 0.9906)
			(stroke
				(width 0.1)
				(type default)
			)
			(layer "F.Fab")
		)
		(pad "1" smd rect
			(at 0 0 180)
			(size 0.508 0.508)
			(layers "F.Cu" "F.Mask" "F.Paste")
			(net "P3V3_STBY")
		)
		(pad "2" smd rect
			(at 0 0.889 180)
			(size 0.508 0.508)
			(layers "F.Cu" "F.Mask" "F.Paste")
			(net "FM_BMC_CPLD_GPO")
		)
		(zone
			(layer "F.Cu")
			(hatch none 0.5)
			(connect_pads
				(clearance 0)
			)
			(min_thickness 0.25)
			(keepout
				(tracks not_allowed)
				(vias allowed)
				(pads allowed)
				(copperpour not_allowed)
				(footprints allowed)
			)
			(placement
				(enabled no)
				(sheetname "")
			)
			(fill
				(thermal_gap 0.5)
				(thermal_bridge_width 0.5)
				(island_removal_mode 0)
			)
			(polygon
				(pts
					(xy 419.3032 -114.6302) (xy 418.7952 -114.6302) (xy 418.7952 -114.2492) (xy 419.3032 -114.2492)
				)
			)
		)
		(zone
			(layer "F.Cu")
			(hatch none 0.5)
			(connect_pads
				(clearance 0)
			)
			(min_thickness 0.25)
			(keepout
				(tracks allowed)
				(vias not_allowed)
				(pads allowed)
				(copperpour not_allowed)
				(footprints allowed)
			)
			(placement
				(enabled no)
				(sheetname "")
			)
			(fill
				(thermal_gap 0.5)
				(thermal_bridge_width 0.5)
				(island_removal_mode 0)
			)
			(polygon
				(pts
					(xy 419.3032 -114.2492) (xy 418.7952 -114.2492) (xy 418.7952 -114.6302) (xy 419.3032 -114.6302)
				)
			)
		)
	)
	(footprint ""
		(layer "F.Cu")
		(at 323.516498 -128.013714 180)
		(property "Reference" "R6B4"
			(at 0 0 180)
			(layer "F.SilkS")
			(hide yes)
			(effects
				(font
					(size 1.27 1.27)
				)
			)
		)
		(property "Value" ""
			(at 0 0 180)
			(layer "F.Fab")
			(effects
				(font
					(size 1.27 1.27)
				)
			)
		)
		(duplicate_pad_numbers_are_jumpers no)
		(fp_poly
			(pts
				(xy -0.2794 -0.1016) (xy 0.2794 -0.1016) (xy 0.2794 0.9906) (xy -0.2794 0.9906)
			)
			(stroke
				(width 0)
				(type default)
			)
			(fill no)
			(layer "F.CrtYd")
		)
		(fp_line
			(start 0.2794 0.9906)
			(end 0.2794 -0.1016)
			(stroke
				(width 0.1)
				(type default)
			)
			(layer "F.Fab")
		)
		(fp_line
			(start 0.2794 -0.1016)
			(end -0.2794 -0.1016)
			(stroke
				(width 0.1)
				(type default)
			)
			(layer "F.Fab")
		)
		(fp_line
			(start -0.2794 0.9906)
			(end 0.2794 0.9906)
			(stroke
				(width 0.1)
				(type default)
			)
			(layer "F.Fab")
		)
		(fp_line
			(start -0.2794 -0.1016)
			(end -0.2794 0.9906)
			(stroke
				(width 0.1)
				(type default)
			)
			(layer "F.Fab")
		)
		(pad "1" smd rect
			(at 0 0 180)
			(size 0.508 0.508)
			(layers "F.Cu" "F.Mask" "F.Paste")
			(net "SVID_DIO1_CPU0")
		)
		(pad "2" smd rect
			(at 0 0.889 180)
			(size 0.508 0.508)
			(layers "F.Cu" "F.Mask" "F.Paste")
			(net "SVID_DIO1_CPU0_R")
		)
		(zone
			(layer "F.Cu")
			(hatch none 0.5)
			(connect_pads
				(clearance 0)
			)
			(min_thickness 0.25)
			(keepout
				(tracks not_allowed)
				(vias allowed)
				(pads allowed)
				(copperpour not_allowed)
				(footprints allowed)
			)
			(placement
				(enabled no)
				(sheetname "")
			)
			(fill
				(thermal_gap 0.5)
				(thermal_bridge_width 0.5)
				(island_removal_mode 0)
			)
			(polygon
				(pts
					(xy 323.770498 -128.648714) (xy 323.262498 -128.648714) (xy 323.262498 -128.267714) (xy 323.770498 -128.267714)
				)
			)
		)
		(zone
			(layer "F.Cu")
			(hatch none 0.5)
			(connect_pads
				(clearance 0)
			)
			(min_thickness 0.25)
			(keepout
				(tracks allowed)
				(vias not_allowed)
				(pads allowed)
				(copperpour not_allowed)
				(footprints allowed)
			)
			(placement
				(enabled no)
				(sheetname "")
			)
			(fill
				(thermal_gap 0.5)
				(thermal_bridge_width 0.5)
				(island_removal_mode 0)
			)
			(polygon
				(pts
					(xy 323.770498 -128.267714) (xy 323.262498 -128.267714) (xy 323.262498 -128.648714) (xy 323.770498 -128.648714)
				)
			)
		)
	)
	(footprint ""
		(layer "F.Cu")
		(at 469.3412 -14.317472 -90)
		(property "Reference" "L8F1"
			(at 0 0 270)
			(layer "F.SilkS")
			(hide yes)
			(effects
				(font
					(size 1.27 1.27)
				)
			)
		)
		(property "Value" "*"
			(at 5.9436 -5.842 270)
			(unlocked yes)
			(layer "F.Fab")
			(hide yes)
			(effects
				(font
					(size 1.27 1.016)
					(thickness 0.1524)
				)
			)
		)
		(property "Device Type" "IND-1UH-361-GP_DISCRET-GC1-INDA"
			(at 5.9436 -7.366 270)
			(unlocked yes)
			(layer "F.Fab")
			(hide yes)
			(effects
				(font
					(size 1.27 1.016)
					(thickness 0.1524)
				)
			)
		)
		(duplicate_pad_numbers_are_jumpers no)
		(fp_line
			(start -4.0005 4.6101)
			(end -4.0005 -4.6101)
			(stroke
				(width 0.1524)
				(type default)
			)
			(layer "F.SilkS")
		)
		(fp_line
			(start 4.0005 4.6101)
			(end -4.0005 4.6101)
			(stroke
				(width 0.1524)
				(type default)
			)
			(layer "F.SilkS")
		)
		(fp_line
			(start -4.0005 -4.6101)
			(end 4.0005 -4.6101)
			(stroke
				(width 0.1524)
				(type default)
			)
			(layer "F.SilkS")
		)
		(fp_line
			(start 4.0005 -4.6101)
			(end 4.0005 4.6101)
			(stroke
				(width 0.1524)
				(type default)
			)
			(layer "F.SilkS")
		)
		(fp_rect
			(start -3.7465 3.5941)
			(end 3.7465 -3.5941)
			(stroke
				(width 0)
				(type default)
			)
			(fill no)
			(layer "F.CrtYd")
		)
		(fp_poly
			(pts
				(xy -4.2545 4.6863) (xy -4.2545 3.5941) (xy 3.7465 3.5941) (xy 3.7465 -3.5941) (xy -3.7465 -3.5941)
				(xy -3.7465 3.5814) (xy -4.2545 3.5814) (xy -4.2545 -4.6863) (xy 4.2545 -4.6863) (xy 4.2545 4.6863)
			)
			(stroke
				(width 0)
				(type default)
			)
			(fill no)
			(layer "F.CrtYd")
		)
		(fp_rect
			(start -4.2545 4.6863)
			(end 4.2545 -4.6863)
			(stroke
				(width 0)
				(type default)
			)
			(fill no)
			(layer "F.Fab")
		)
		(pad "1" smd rect
			(at 0 -3.039872 270)
			(size 5.5118 2.6416)
			(layers "F.Cu" "F.Mask" "F.Paste")
			(net "VR_P3V3_STBY_PHASE")
		)
		(pad "2" smd rect
			(at 0 3.039872 270)
			(size 5.5118 2.6416)
			(layers "F.Cu" "F.Mask" "F.Paste")
			(net "P3V3_STBY")
		)
	)
	(footprint ""
		(layer "F.Cu")
		(at 483.6414 -125.222 -90)
		(property "Reference" "J9B2"
			(at 2.69367 0.889 0)
			(unlocked yes)
			(layer "B.SilkS")
			(effects
				(font
					(size 0.7874 0.5842)
					(thickness 0.1524)
				)
				(justify left mirror)
			)
		)
		(property "Value" ""
			(at 0 0 270)
			(layer "F.Fab")
			(effects
				(font
					(size 1.27 1.27)
				)
			)
		)
		(duplicate_pad_numbers_are_jumpers no)
		(fp_line
			(start -1.27 6.54939)
			(end -1.27 -1.46939)
			(stroke
				(width 0.1524)
				(type default)
			)
			(layer "F.SilkS")
		)
		(fp_line
			(start 1.27 6.54939)
			(end -1.27 6.54939)
			(stroke
				(width 0.1524)
				(type default)
			)
			(layer "F.SilkS")
		)
		(fp_line
			(start -1.27 -1.46939)
			(end 1.27 -1.46939)
			(stroke
				(width 0.1524)
				(type default)
			)
			(layer "F.SilkS")
		)
		(fp_line
			(start 1.27 -1.46939)
			(end 1.27 6.54939)
			(stroke
				(width 0.1524)
				(type default)
			)
			(layer "F.SilkS")
		)
		(fp_poly
			(pts
				(xy -3.17246 0.38862) (xy -3.17246 -0.62738) (xy -1.90246 -0.11938)
			)
			(stroke
				(width 0)
				(type default)
			)
			(fill yes)
			(layer "F.SilkS")
		)
		(fp_poly
			(pts
				(xy -3.17246 0.38862) (xy -3.17246 -0.62738) (xy -1.90246 -0.11938)
			)
			(stroke
				(width 0)
				(type default)
			)
			(fill yes)
			(layer "B.SilkS")
		)
		(fp_poly
			(pts
				(xy 1.27 6.54939) (xy 1.27 -1.46939) (xy -1.27 -1.46939) (xy -1.27 6.54939)
			)
			(stroke
				(width 0)
				(type default)
			)
			(fill no)
			(layer "F.CrtYd")
		)
		(fp_poly
			(pts
				(xy -3.17246 0.38862) (xy -3.17246 -0.62738) (xy -1.90246 -0.11938)
			)
			(stroke
				(width 0)
				(type default)
			)
			(fill yes)
			(layer "B.Fab")
		)
		(fp_line
			(start -1.27 6.54939)
			(end -1.27 -1.46939)
			(stroke
				(width 0.1)
				(type default)
			)
			(layer "F.Fab")
		)
		(fp_line
			(start 1.27 6.54939)
			(end -1.27 6.54939)
			(stroke
				(width 0.1)
				(type default)
			)
			(layer "F.Fab")
		)
		(fp_line
			(start -1.27 -1.46939)
			(end 1.27 -1.46939)
			(stroke
				(width 0.1)
				(type default)
			)
			(layer "F.Fab")
		)
		(fp_line
			(start 1.27 -1.46939)
			(end 1.27 6.54939)
			(stroke
				(width 0.1)
				(type default)
			)
			(layer "F.Fab")
		)
		(fp_poly
			(pts
				(xy -3.17246 0.38862) (xy -3.17246 -0.62738) (xy -1.90246 -0.11938)
			)
			(stroke
				(width 0)
				(type default)
			)
			(fill yes)
			(layer "F.Fab")
		)
		(fp_text user "3"
			(at 0.188976 7.44728 0)
			(unlocked yes)
			(layer "F.SilkS")
			(effects
				(font
					(size 0.7874 0.5842)
					(thickness 0.1524)
				)
				(justify left)
			)
		)
		(fp_text user "3"
			(at -1.60655 3.38582 0)
			(unlocked yes)
			(layer "B.SilkS")
			(effects
				(font
					(size 0.7874 0.5842)
					(thickness 0.1524)
				)
				(justify left mirror)
			)
		)
		(fp_text user "3"
			(at -1.82626 5.08127 270)
			(unlocked yes)
			(layer "B.Fab")
			(effects
				(font
					(size 0.7874 0.5842)
					(thickness 0.1524)
				)
				(justify left mirror)
			)
		)
		(fp_text user "3"
			(at 0.187706 7.4422 0)
			(unlocked yes)
			(layer "F.Fab")
			(effects
				(font
					(size 0.7874 0.5842)
					(thickness 0.1524)
				)
				(justify left)
			)
		)
		(pad "1" thru_hole rect
			(at 0 0 270)
			(size 1.524 1.524)
			(drill 1.143)
			(layers "*.Cu" "*.Mask")
			(remove_unused_layers no)
			(net "SMB_SMLINK0_STBY_LVC3_SDA")
			(clearance 0.127)
			(thermal_gap 0.127)
			(padstack
				(mode front_inner_back)
				(layer "Inner"
					(shape circle)
					(size 1.524 1.524)
					(clearance 0.127)
				)
				(layer "B.Cu"
					(shape rect)
					(size 1.524 1.524)
					(clearance 0.127)
				)
			)
		)
		(pad "2" thru_hole circle
			(at 0 2.54 270)
			(size 1.524 1.524)
			(drill 1.143)
			(layers "*.Cu" "*.Mask")
			(remove_unused_layers no)
			(net "GND")
			(clearance 0.127)
			(thermal_gap 0.127)
		)
		(pad "3" thru_hole circle
			(at 0 5.08 270)
			(size 1.524 1.524)
			(drill 1.143)
			(layers "*.Cu" "*.Mask")
			(remove_unused_layers no)
			(net "SMB_SMLINK0_STBY_LVC3_SCL")
			(clearance 0.127)
			(thermal_gap 0.127)
		)
	)
	(footprint ""
		(layer "F.Cu")
		(at 374.015 -89.0905 180)
		(property "Reference" "R2P2"
			(at 0 0 180)
			(layer "F.SilkS")
			(hide yes)
			(effects
				(font
					(size 1.27 1.27)
				)
			)
		)
		(property "Value" ""
			(at 0 0 180)
			(layer "F.Fab")
			(effects
				(font
					(size 1.27 1.27)
				)
			)
		)
		(duplicate_pad_numbers_are_jumpers no)
		(fp_rect
			(start 0.2794 -0.1016)
			(end -0.2794 0.9906)
			(stroke
				(width 0)
				(type default)
			)
			(fill no)
			(layer "F.CrtYd")
		)
		(fp_line
			(start 0.2794 0.9906)
			(end 0.2794 -0.1016)
			(stroke
				(width 0.1)
				(type default)
			)
			(layer "F.Fab")
		)
		(fp_line
			(start 0.2794 -0.1016)
			(end -0.2794 -0.1016)
			(stroke
				(width 0.1)
				(type default)
			)
			(layer "F.Fab")
		)
		(fp_line
			(start -0.2794 0.9906)
			(end 0.2794 0.9906)
			(stroke
				(width 0.1)
				(type default)
			)
			(layer "F.Fab")
		)
		(fp_line
			(start -0.2794 -0.1016)
			(end -0.2794 0.9906)
			(stroke
				(width 0.1)
				(type default)
			)
			(layer "F.Fab")
		)
		(pad "1" smd rect
			(at 0 0 180)
			(size 0.508 0.508)
			(layers "F.Cu" "F.Mask" "F.Paste")
			(net "SPI_PCH_IO2")
		)
		(pad "2" smd rect
			(at 0 0.889 180)
			(size 0.508 0.508)
			(layers "F.Cu" "F.Mask" "F.Paste")
			(net "XDP_DEBUG_CONSENT_N")
		)
		(zone
			(layer "F.Cu")
			(hatch none 0.5)
			(connect_pads
				(clearance 0)
			)
			(min_thickness 0.25)
			(keepout
				(tracks allowed)
				(vias not_allowed)
				(pads allowed)
				(copperpour not_allowed)
				(footprints allowed)
			)
			(placement
				(enabled no)
				(sheetname "")
			)
			(fill
				(thermal_gap 0.5)
				(thermal_bridge_width 0.5)
				(island_removal_mode 0)
			)
			(polygon
				(pts
					(xy 373.761 -89.3445) (xy 374.269 -89.3445) (xy 374.269 -89.7255) (xy 373.761 -89.7255)
				)
			)
		)
		(zone
			(layer "F.Cu")
			(hatch none 0.5)
			(connect_pads
				(clearance 0)
			)
			(min_thickness 0.25)
			(keepout
				(tracks not_allowed)
				(vias allowed)
				(pads allowed)
				(copperpour not_allowed)
				(footprints allowed)
			)
			(placement
				(enabled no)
				(sheetname "")
			)
			(fill
				(thermal_gap 0.5)
				(thermal_bridge_width 0.5)
				(island_removal_mode 0)
			)
			(polygon
				(pts
					(xy 373.761 -89.3445) (xy 374.269 -89.3445) (xy 374.269 -89.7255) (xy 373.761 -89.7255)
				)
			)
		)
	)
	(footprint ""
		(layer "F.Cu")
		(at -3.429 -124.333 180)
		(property "Reference" "R1B16"
			(at 0 0 180)
			(layer "F.SilkS")
			(hide yes)
			(effects
				(font
					(size 1.27 1.27)
				)
			)
		)
		(property "Value" ""
			(at 0 0 180)
			(layer "F.Fab")
			(effects
				(font
					(size 1.27 1.27)
				)
			)
		)
		(duplicate_pad_numbers_are_jumpers no)
		(fp_rect
			(start 0.2794 -0.1016)
			(end -0.2794 0.9906)
			(stroke
				(width 0)
				(type default)
			)
			(fill no)
			(layer "F.CrtYd")
		)
		(fp_line
			(start 0.2794 0.9906)
			(end 0.2794 -0.1016)
			(stroke
				(width 0.1)
				(type default)
			)
			(layer "F.Fab")
		)
		(fp_line
			(start 0.2794 -0.1016)
			(end -0.2794 -0.1016)
			(stroke
				(width 0.1)
				(type default)
			)
			(layer "F.Fab")
		)
		(fp_line
			(start -0.2794 0.9906)
			(end 0.2794 0.9906)
			(stroke
				(width 0.1)
				(type default)
			)
			(layer "F.Fab")
		)
		(fp_line
			(start -0.2794 -0.1016)
			(end -0.2794 0.9906)
			(stroke
				(width 0.1)
				(type default)
			)
			(layer "F.Fab")
		)
		(pad "1" smd rect
			(at 0 0 180)
			(size 0.508 0.508)
			(layers "F.Cu" "F.Mask" "F.Paste")
			(net "VSENSE_PVDDQ_KLM_P")
		)
		(pad "2" smd rect
			(at 0 0.889 180)
			(size 0.508 0.508)
			(layers "F.Cu" "F.Mask" "F.Paste")
			(net "VR_PVDDQ_KLM_AVSP")
		)
		(zone
			(layer "F.Cu")
			(hatch none 0.5)
			(connect_pads
				(clearance 0)
			)
			(min_thickness 0.25)
			(keepout
				(tracks allowed)
				(vias not_allowed)
				(pads allowed)
				(copperpour not_allowed)
				(footprints allowed)
			)
			(placement
				(enabled no)
				(sheetname "")
			)
			(fill
				(thermal_gap 0.5)
				(thermal_bridge_width 0.5)
				(island_removal_mode 0)
			)
			(polygon
				(pts
					(xy -3.683 -124.587) (xy -3.175 -124.587) (xy -3.175 -124.968) (xy -3.683 -124.968)
				)
			)
		)
		(zone
			(layer "F.Cu")
			(hatch none 0.5)
			(connect_pads
				(clearance 0)
			)
			(min_thickness 0.25)
			(keepout
				(tracks not_allowed)
				(vias allowed)
				(pads allowed)
				(copperpour not_allowed)
				(footprints allowed)
			)
			(placement
				(enabled no)
				(sheetname "")
			)
			(fill
				(thermal_gap 0.5)
				(thermal_bridge_width 0.5)
				(island_removal_mode 0)
			)
			(polygon
				(pts
					(xy -3.683 -124.587) (xy -3.175 -124.587) (xy -3.175 -124.968) (xy -3.683 -124.968)
				)
			)
		)
	)
)
